(kicad_pcb
	(version 20260206)
	(generator "pcbnew")
	(generator_version "10.0")
	(general
		(thickness 1.6)
		(legacy_teardrops no)
	)
	(paper "A4")
	(title_block
		(title "v2-pdb — ms_pdb_v2.brd")
		(comment 1 "Open CloudServer (Microsoft) / footprints 181-190 of 348")
	)
	(layers
		(0 "F.Cu" signal "TOP")
		(4 "In1.Cu" signal "GND")
		(6 "In2.Cu" signal "IN1")
		(8 "In3.Cu" signal "VCC")
		(10 "In4.Cu" signal "VCC1")
		(12 "In5.Cu" signal "IN2")
		(14 "In6.Cu" signal "GND1")
		(2 "B.Cu" signal "BOTTOM")
		(9 "F.Adhes" user "F.Adhesive")
		(11 "B.Adhes" user "B.Adhesive")
		(13 "F.Paste" user "Package Geometry/Pastemask Top")
		(15 "B.Paste" user "Package Geometry/Pastemask Bottom")
		(5 "F.SilkS" user "Ref Des/Silkscreen Top")
		(7 "B.SilkS" user "Ref Des/Silkscreen Bottom")
		(1 "F.Mask" user "Board Geometry/Soldermask Top")
		(3 "B.Mask" user "Board Geometry/Soldermask Bottom")
		(17 "Dwgs.User" user "User.Drawings")
		(19 "Cmts.User" user "User.Comments")
		(21 "Eco1.User" user "User.Eco1")
		(23 "Eco2.User" user "User.Eco2")
		(25 "Edge.Cuts" user "Board Geometry/Outline")
		(27 "Margin" user)
		(31 "F.CrtYd" user "Package Geometry/Place Bound Top")
		(29 "B.CrtYd" user "Package Geometry/Place Bound Bottom")
		(35 "F.Fab" user "Ref Des/Assembly Top")
		(33 "B.Fab" user "Ref Des/Assembly Bottom")
	)
	(footprint ""
		(layer "F.Cu")
		(at 50.083466 -38.6207 180)
		(property "Reference" "CE2"
			(at 1.317244 -5.56133 0)
			(unlocked yes)
			(layer "F.SilkS")
			(effects
				(font
					(size 0.7874 0.5842)
					(thickness 0.1524)
				)
				(justify left)
			)
		)
		(property "Value" ""
			(at 0 0 180)
			(layer "F.Fab")
			(effects
				(font
					(size 1.27 1.27)
				)
			)
		)
		(duplicate_pad_numbers_are_jumpers no)
		(fp_line
			(start 0 -4.2672)
			(end 0 4.2672)
			(stroke
				(width 0.1524)
				(type default)
			)
			(layer "F.SilkS")
		)
		(fp_circle
			(center 0 0)
			(end -4.2672 0)
			(stroke
				(width 0.1524)
				(type default)
			)
			(fill no)
			(layer "F.SilkS")
		)
		(fp_poly
			(pts
				(arc
					(start 0 -4.2672)
					(mid 4.2672 0)
					(end 0 4.2672)
				)
			)
			(stroke
				(width 0)
				(type default)
			)
			(fill yes)
			(layer "F.SilkS")
		)
		(fp_poly
			(pts
				(xy -2.5146 -0.762) (xy -0.9906 -0.762) (xy -0.9906 0.762) (xy -2.5146 0.762)
			)
			(stroke
				(width 0)
				(type default)
			)
			(fill no)
			(layer "B.CrtYd")
		)
		(fp_poly
			(pts
				(arc
					(start 1.7526 0.762)
					(mid 2.291415 -0.538815)
					(end 0.9906 0)
				)
				(arc
					(start 0.9906 0.0254)
					(mid 1.206345 0.546255)
					(end 1.7272 0.762)
				)
			)
			(stroke
				(width 0)
				(type default)
			)
			(fill no)
			(layer "B.CrtYd")
		)
		(fp_poly
			(pts
				(arc
					(start -4.2672 0)
					(mid 4.2672 0)
					(end -4.2672 0)
				)
			)
			(stroke
				(width 0)
				(type default)
			)
			(fill no)
			(layer "F.CrtYd")
		)
		(fp_circle
			(center 0 0)
			(end -4.2672 0)
			(stroke
				(width 0.1)
				(type default)
			)
			(fill no)
			(layer "F.Fab")
		)
		(fp_text user "+"
			(at -4.383532 3.495548 180)
			(unlocked yes)
			(layer "F.SilkS")
			(effects
				(font
					(size 1.905 1.4224)
					(thickness 0.1524)
				)
				(justify left)
			)
		)
		(fp_text user "+"
			(at -5.6642 -0.34925 180)
			(unlocked yes)
			(layer "F.Fab")
			(effects
				(font
					(size 1.905 1.4224)
					(thickness 0.000001)
				)
				(justify left)
			)
		)
		(pad "1" thru_hole rect
			(at -1.75006 0 180)
			(size 1.397 1.397)
			(drill 0.9144)
			(layers "*.Cu" "*.Mask")
			(remove_unused_layers no)
			(net "P12V")
			(clearance 0.0127)
			(thermal_gap 0.0127)
			(padstack
				(mode front_inner_back)
				(layer "Inner"
					(shape circle)
					(size 1.397 1.397)
					(clearance 0.0127)
				)
				(layer "B.Cu"
					(shape rect)
					(size 1.397 1.397)
					(clearance 0.0127)
				)
			)
		)
		(pad "2" thru_hole circle
			(at 1.75006 0 180)
			(size 1.397 1.397)
			(drill 0.9144)
			(layers "*.Cu" "*.Mask")
			(remove_unused_layers no)
			(net "GND")
			(clearance 0.0127)
			(thermal_gap 0.0127)
		)
	)
	(footprint ""
		(layer "F.Cu")
		(at 25.997662 -8.344662)
		(property "Reference" "R43"
			(at -3.764788 0.113792 0)
			(unlocked yes)
			(layer "F.SilkS")
			(effects
				(font
					(size 0.7874 0.5842)
					(thickness 0.1524)
				)
				(justify left)
			)
		)
		(property "Value" ""
			(at 0 0 0)
			(layer "F.Fab")
			(effects
				(font
					(size 1.27 1.27)
				)
			)
		)
		(duplicate_pad_numbers_are_jumpers no)
		(fp_line
			(start -0.7874 -0.4064)
			(end 0.7874 -0.4064)
			(stroke
				(width 0.1524)
				(type default)
			)
			(layer "F.SilkS")
		)
		(fp_line
			(start -0.7874 0.4064)
			(end -0.7874 -0.4064)
			(stroke
				(width 0.1524)
				(type default)
			)
			(layer "F.SilkS")
		)
		(fp_line
			(start 0.7874 -0.4064)
			(end 0.7874 0.4064)
			(stroke
				(width 0.1524)
				(type default)
			)
			(layer "F.SilkS")
		)
		(fp_line
			(start 0.7874 0.4064)
			(end -0.7874 0.4064)
			(stroke
				(width 0.1524)
				(type default)
			)
			(layer "F.SilkS")
		)
		(fp_poly
			(pts
				(xy -0.508 0.2794) (xy -0.508 0.2286) (xy -0.635 0.2286) (xy -0.635 -0.254) (xy -0.5334 -0.254)
				(xy -0.5334 -0.2794) (xy 0.5334 -0.2794) (xy 0.5334 -0.254) (xy 0.635 -0.254) (xy 0.635 0.254) (xy 0.5334 0.254)
				(xy 0.5334 0.2794)
			)
			(stroke
				(width 0)
				(type default)
			)
			(fill no)
			(layer "F.CrtYd")
		)
		(pad "1" smd rect
			(at 0.40005 0)
			(size 0.4572 0.508)
			(layers "F.Cu" "F.Mask" "F.Paste")
			(net "PSU1_PS_KILL")
		)
		(pad "2" smd rect
			(at -0.40005 0)
			(size 0.4572 0.508)
			(layers "F.Cu" "F.Mask" "F.Paste")
			(net "GND")
		)
	)
	(footprint ""
		(layer "F.Cu")
		(at 72.478392 -153.431748 -90)
		(property "Reference" "C22"
			(at -3.210052 -0.035814 90)
			(unlocked yes)
			(layer "F.SilkS")
			(effects
				(font
					(size 0.7874 0.5842)
					(thickness 0.1524)
				)
			)
		)
		(property "Value" ""
			(at 0 0 270)
			(layer "F.Fab")
			(effects
				(font
					(size 1.27 1.27)
				)
			)
		)
		(duplicate_pad_numbers_are_jumpers no)
		(fp_line
			(start -1.2954 0.5842)
			(end -1.2954 -0.5842)
			(stroke
				(width 0.1524)
				(type default)
			)
			(layer "F.SilkS")
		)
		(fp_line
			(start 1.2954 0.5842)
			(end -1.2954 0.5842)
			(stroke
				(width 0.1524)
				(type default)
			)
			(layer "F.SilkS")
		)
		(fp_line
			(start -1.2954 -0.5842)
			(end 1.2954 -0.5842)
			(stroke
				(width 0.1524)
				(type default)
			)
			(layer "F.SilkS")
		)
		(fp_line
			(start 0 -0.5842)
			(end 0 0.5842)
			(stroke
				(width 0.1524)
				(type default)
			)
			(layer "F.SilkS")
		)
		(fp_line
			(start 1.2954 -0.5842)
			(end 1.2954 0.5842)
			(stroke
				(width 0.1524)
				(type default)
			)
			(layer "F.SilkS")
		)
		(fp_poly
			(pts
				(xy 0.8636 -0.4572) (xy 0.8636 -0.3556) (xy 1.143 -0.3556) (xy 1.143 0.3556) (xy 0.8636 0.3556)
				(xy 0.8636 0.4572) (xy -0.8636 0.4572) (xy -0.8636 0.3556) (xy -1.143 0.3556) (xy -1.143 -0.3556)
				(xy -0.8636 -0.3556) (xy -0.8636 -0.4572)
			)
			(stroke
				(width 0)
				(type default)
			)
			(fill no)
			(layer "F.CrtYd")
		)
		(fp_line
			(start -0.884936 0.504952)
			(end -0.884936 -0.504952)
			(stroke
				(width 0.1)
				(type default)
			)
			(layer "F.Fab")
		)
		(fp_line
			(start 0.884936 0.504952)
			(end -0.884936 0.504952)
			(stroke
				(width 0.1)
				(type default)
			)
			(layer "F.Fab")
		)
		(fp_line
			(start -0.884936 -0.504952)
			(end 0.884936 -0.504952)
			(stroke
				(width 0.1)
				(type default)
			)
			(layer "F.Fab")
		)
		(fp_line
			(start 0.884936 -0.504952)
			(end 0.884936 0.504952)
			(stroke
				(width 0.1)
				(type default)
			)
			(layer "F.Fab")
		)
		(pad "1" smd rect
			(at 0.7366 0)
			(size 0.7112 0.8128)
			(layers "F.Cu" "F.Mask" "F.Paste")
			(net "P12V")
		)
		(pad "2" smd rect
			(at -0.7366 0)
			(size 0.7112 0.8128)
			(layers "F.Cu" "F.Mask" "F.Paste")
			(net "GND")
		)
	)
	(footprint ""
		(layer "F.Cu")
		(at 72.520302 -83.335368 90)
		(property "Reference" "C20"
			(at 1.029716 -0.015748 90)
			(unlocked yes)
			(layer "F.SilkS")
			(effects
				(font
					(size 0.7874 0.5842)
					(thickness 0.1524)
				)
				(justify left)
			)
		)
		(property "Value" ""
			(at 0 0 90)
			(layer "F.Fab")
			(effects
				(font
					(size 1.27 1.27)
				)
			)
		)
		(duplicate_pad_numbers_are_jumpers no)
		(fp_line
			(start 0.7874 -0.4064)
			(end 0.7874 0.4064)
			(stroke
				(width 0.1524)
				(type default)
			)
			(layer "F.SilkS")
		)
		(fp_line
			(start -0.7874 -0.4064)
			(end 0.7874 -0.4064)
			(stroke
				(width 0.1524)
				(type default)
			)
			(layer "F.SilkS")
		)
		(fp_line
			(start 0 0.381)
			(end 0 -0.381)
			(stroke
				(width 0.1524)
				(type default)
			)
			(layer "F.SilkS")
		)
		(fp_line
			(start 0.7874 0.4064)
			(end -0.7874 0.4064)
			(stroke
				(width 0.1524)
				(type default)
			)
			(layer "F.SilkS")
		)
		(fp_line
			(start -0.7874 0.4064)
			(end -0.7874 -0.4064)
			(stroke
				(width 0.1524)
				(type default)
			)
			(layer "F.SilkS")
		)
		(fp_poly
			(pts
				(xy -0.5334 0.254) (xy -0.635 0.254) (xy -0.635 0.2286) (xy -0.635 -0.254) (xy -0.5334 -0.254) (xy -0.5334 -0.2794)
				(xy 0.5334 -0.2794) (xy 0.5334 -0.254) (xy 0.635 -0.254) (xy 0.635 0.254) (xy 0.5334 0.254) (xy 0.5334 0.2794)
				(xy -0.508 0.2794) (xy -0.5334 0.2794)
			)
			(stroke
				(width 0)
				(type default)
			)
			(fill no)
			(layer "F.CrtYd")
		)
		(pad "1" smd rect
			(at 0.40005 0 90)
			(size 0.4572 0.508)
			(layers "F.Cu" "F.Mask" "F.Paste")
			(net "P12V")
		)
		(pad "2" smd rect
			(at -0.40005 0 90)
			(size 0.4572 0.508)
			(layers "F.Cu" "F.Mask" "F.Paste")
			(net "GND")
		)
	)
	(footprint ""
		(layer "F.Cu")
		(at 91.399868 -20.01012)
		(property "Reference" "H25"
			(at -5.1308 -5.23113 0)
			(unlocked yes)
			(layer "F.SilkS")
			(effects
				(font
					(size 0.7874 0.5842)
					(thickness 0.1524)
				)
				(justify left)
			)
		)
		(property "Value" ""
			(at 0 0 0)
			(layer "F.Fab")
			(effects
				(font
					(size 1.27 1.27)
				)
			)
		)
		(duplicate_pad_numbers_are_jumpers no)
		(fp_circle
			(center 0 0)
			(end 4.826 0)
			(stroke
				(width 0.1524)
				(type default)
			)
			(fill no)
			(layer "F.SilkS")
		)
		(fp_circle
			(center 0 0)
			(end 4.826 0)
			(stroke
				(width 0.1524)
				(type default)
			)
			(fill no)
			(layer "B.SilkS")
		)
		(fp_poly
			(pts
				(arc
					(start 0 4.0132)
					(mid 0 -4.0132)
					(end 0 4.0132)
				)
			)
			(stroke
				(width 0)
				(type default)
			)
			(fill no)
			(layer "F.CrtYd")
		)
		(pad "" np_thru_hole circle
			(at 0 0)
			(size 8.001 8.001)
			(drill 8.001)
			(layers "*.Cu" "*.Mask")
			(clearance 0.381)
			(thermal_gap 0.381)
		)
		(zone
			(layers "F.Cu" "B.Cu" "In1.Cu" "In2.Cu" "In3.Cu" "In4.Cu" "In5.Cu" "In6.Cu")
			(hatch none 0.5)
			(connect_pads
				(clearance 0)
			)
			(min_thickness 0.25)
			(keepout
				(tracks not_allowed)
				(vias allowed)
				(pads allowed)
				(copperpour not_allowed)
				(footprints allowed)
			)
			(placement
				(enabled no)
				(sheetname "")
			)
			(fill
				(thermal_gap 0.5)
				(thermal_bridge_width 0.5)
				(island_removal_mode 0)
			)
			(polygon
				(pts
					(arc
						(start 91.399868 -15.48892)
						(mid 91.399868 -24.53132)
						(end 91.399868 -15.48892)
					)
				)
			)
		)
	)
	(footprint ""
		(layer "F.Cu")
		(at 13.463778 -325.064882 180)
		(property "Reference" "R142"
			(at -1.647444 -0.037592 0)
			(unlocked yes)
			(layer "F.SilkS")
			(effects
				(font
					(size 0.7874 0.5842)
					(thickness 0.1524)
				)
				(justify left)
			)
		)
		(property "Value" ""
			(at 0 0 180)
			(layer "F.Fab")
			(effects
				(font
					(size 1.27 1.27)
				)
			)
		)
		(duplicate_pad_numbers_are_jumpers no)
		(fp_line
			(start 0.7874 0.4064)
			(end -0.7874 0.4064)
			(stroke
				(width 0.1524)
				(type default)
			)
			(layer "F.SilkS")
		)
		(fp_line
			(start 0.7874 -0.4064)
			(end 0.7874 0.4064)
			(stroke
				(width 0.1524)
				(type default)
			)
			(layer "F.SilkS")
		)
		(fp_line
			(start -0.7874 0.4064)
			(end -0.7874 -0.4064)
			(stroke
				(width 0.1524)
				(type default)
			)
			(layer "F.SilkS")
		)
		(fp_line
			(start -0.7874 -0.4064)
			(end 0.7874 -0.4064)
			(stroke
				(width 0.1524)
				(type default)
			)
			(layer "F.SilkS")
		)
		(fp_poly
			(pts
				(xy -0.508 0.2794) (xy -0.508 0.2286) (xy -0.635 0.2286) (xy -0.635 -0.254) (xy -0.5334 -0.254)
				(xy -0.5334 -0.2794) (xy 0.5334 -0.2794) (xy 0.5334 -0.254) (xy 0.635 -0.254) (xy 0.635 0.254) (xy 0.5334 0.254)
				(xy 0.5334 0.2794)
			)
			(stroke
				(width 0)
				(type default)
			)
			(fill no)
			(layer "F.CrtYd")
		)
		(pad "1" smd rect
			(at 0.40005 0 180)
			(size 0.4572 0.508)
			(layers "F.Cu" "F.Mask" "F.Paste")
			(net "FAN1_TACH")
		)
		(pad "2" smd rect
			(at -0.40005 0 180)
			(size 0.4572 0.508)
			(layers "F.Cu" "F.Mask" "F.Paste")
			(net "P12V")
		)
	)
	(footprint ""
		(layer "F.Cu")
		(at 17.162272 -330.455524 -90)
		(property "Reference" "R37"
			(at 3.685032 -0.234188 90)
			(unlocked yes)
			(layer "F.SilkS")
			(effects
				(font
					(size 0.7874 0.5842)
					(thickness 0.1524)
				)
				(justify left)
			)
		)
		(property "Value" ""
			(at 0 0 270)
			(layer "F.Fab")
			(effects
				(font
					(size 1.27 1.27)
				)
			)
		)
		(duplicate_pad_numbers_are_jumpers no)
		(fp_line
			(start -0.7874 0.4064)
			(end -0.7874 -0.4064)
			(stroke
				(width 0.1524)
				(type default)
			)
			(layer "F.SilkS")
		)
		(fp_line
			(start 0.7874 0.4064)
			(end -0.7874 0.4064)
			(stroke
				(width 0.1524)
				(type default)
			)
			(layer "F.SilkS")
		)
		(fp_line
			(start -0.7874 -0.4064)
			(end 0.7874 -0.4064)
			(stroke
				(width 0.1524)
				(type default)
			)
			(layer "F.SilkS")
		)
		(fp_line
			(start 0.7874 -0.4064)
			(end 0.7874 0.4064)
			(stroke
				(width 0.1524)
				(type default)
			)
			(layer "F.SilkS")
		)
		(fp_poly
			(pts
				(xy -0.508 0.2794) (xy -0.508 0.2286) (xy -0.635 0.2286) (xy -0.635 -0.254) (xy -0.5334 -0.254)
				(xy -0.5334 -0.2794) (xy 0.5334 -0.2794) (xy 0.5334 -0.254) (xy 0.635 -0.254) (xy 0.635 0.254) (xy 0.5334 0.254)
				(xy 0.5334 0.2794)
			)
			(stroke
				(width 0)
				(type default)
			)
			(fill no)
			(layer "F.CrtYd")
		)
		(pad "1" smd rect
			(at 0.40005 0 270)
			(size 0.4572 0.508)
			(layers "F.Cu" "F.Mask" "F.Paste")
			(net "GND")
		)
		(pad "2" smd rect
			(at -0.40005 0 270)
			(size 0.4572 0.508)
			(layers "F.Cu" "F.Mask" "F.Paste")
			(net "FRU_A0")
		)
	)
	(footprint ""
		(layer "F.Cu")
		(at 16.017494 -330.497434 -90)
		(property "Reference" "R38"
			(at 3.685032 -0.234188 90)
			(unlocked yes)
			(layer "F.SilkS")
			(effects
				(font
					(size 0.7874 0.5842)
					(thickness 0.1524)
				)
				(justify left)
			)
		)
		(property "Value" ""
			(at 0 0 270)
			(layer "F.Fab")
			(effects
				(font
					(size 1.27 1.27)
				)
			)
		)
		(duplicate_pad_numbers_are_jumpers no)
		(fp_line
			(start -0.7874 0.4064)
			(end -0.7874 -0.4064)
			(stroke
				(width 0.1524)
				(type default)
			)
			(layer "F.SilkS")
		)
		(fp_line
			(start 0.7874 0.4064)
			(end -0.7874 0.4064)
			(stroke
				(width 0.1524)
				(type default)
			)
			(layer "F.SilkS")
		)
		(fp_line
			(start -0.7874 -0.4064)
			(end 0.7874 -0.4064)
			(stroke
				(width 0.1524)
				(type default)
			)
			(layer "F.SilkS")
		)
		(fp_line
			(start 0.7874 -0.4064)
			(end 0.7874 0.4064)
			(stroke
				(width 0.1524)
				(type default)
			)
			(layer "F.SilkS")
		)
		(fp_poly
			(pts
				(xy -0.508 0.2794) (xy -0.508 0.2286) (xy -0.635 0.2286) (xy -0.635 -0.254) (xy -0.5334 -0.254)
				(xy -0.5334 -0.2794) (xy 0.5334 -0.2794) (xy 0.5334 -0.254) (xy 0.635 -0.254) (xy 0.635 0.254) (xy 0.5334 0.254)
				(xy 0.5334 0.2794)
			)
			(stroke
				(width 0)
				(type default)
			)
			(fill no)
			(layer "F.CrtYd")
		)
		(pad "1" smd rect
			(at 0.40005 0 270)
			(size 0.4572 0.508)
			(layers "F.Cu" "F.Mask" "F.Paste")
			(net "GND")
		)
		(pad "2" smd rect
			(at -0.40005 0 270)
			(size 0.4572 0.508)
			(layers "F.Cu" "F.Mask" "F.Paste")
			(net "FRU_A1")
		)
	)
	(footprint ""
		(layer "F.Cu")
		(at 66.689986 -304.009806 90)
		(property "Reference" "C56"
			(at 1.090422 -0.062738 90)
			(unlocked yes)
			(layer "F.SilkS")
			(effects
				(font
					(size 0.7874 0.5842)
					(thickness 0.1524)
				)
				(justify left)
			)
		)
		(property "Value" ""
			(at 0 0 90)
			(layer "F.Fab")
			(effects
				(font
					(size 1.27 1.27)
				)
			)
		)
		(duplicate_pad_numbers_are_jumpers no)
		(fp_line
			(start 0.7874 -0.4064)
			(end 0.7874 0.4064)
			(stroke
				(width 0.1524)
				(type default)
			)
			(layer "F.SilkS")
		)
		(fp_line
			(start -0.7874 -0.4064)
			(end 0.7874 -0.4064)
			(stroke
				(width 0.1524)
				(type default)
			)
			(layer "F.SilkS")
		)
		(fp_line
			(start 0 0.381)
			(end 0 -0.381)
			(stroke
				(width 0.1524)
				(type default)
			)
			(layer "F.SilkS")
		)
		(fp_line
			(start 0.7874 0.4064)
			(end -0.7874 0.4064)
			(stroke
				(width 0.1524)
				(type default)
			)
			(layer "F.SilkS")
		)
		(fp_line
			(start -0.7874 0.4064)
			(end -0.7874 -0.4064)
			(stroke
				(width 0.1524)
				(type default)
			)
			(layer "F.SilkS")
		)
		(fp_poly
			(pts
				(xy -0.5334 0.254) (xy -0.635 0.254) (xy -0.635 0.2286) (xy -0.635 -0.254) (xy -0.5334 -0.254) (xy -0.5334 -0.2794)
				(xy 0.5334 -0.2794) (xy 0.5334 -0.254) (xy 0.635 -0.254) (xy 0.635 0.254) (xy 0.5334 0.254) (xy 0.5334 0.2794)
				(xy -0.508 0.2794) (xy -0.5334 0.2794)
			)
			(stroke
				(width 0)
				(type default)
			)
			(fill no)
			(layer "F.CrtYd")
		)
		(pad "1" smd rect
			(at 0.40005 0 90)
			(size 0.4572 0.508)
			(layers "F.Cu" "F.Mask" "F.Paste")
			(net "P12V")
		)
		(pad "2" smd rect
			(at -0.40005 0 90)
			(size 0.4572 0.508)
			(layers "F.Cu" "F.Mask" "F.Paste")
			(net "GND")
		)
	)
	(footprint ""
		(layer "F.Cu")
		(at 25.857708 -366.710722)
		(property "Reference" "R58"
			(at -3.917442 -0.225298 0)
			(unlocked yes)
			(layer "F.SilkS")
			(effects
				(font
					(size 0.7874 0.5842)
					(thickness 0.1524)
				)
				(justify left)
			)
		)
		(property "Value" ""
			(at 0 0 0)
			(layer "F.Fab")
			(effects
				(font
					(size 1.27 1.27)
				)
			)
		)
		(duplicate_pad_numbers_are_jumpers no)
		(fp_line
			(start -0.7874 -0.4064)
			(end 0.7874 -0.4064)
			(stroke
				(width 0.1524)
				(type default)
			)
			(layer "F.SilkS")
		)
		(fp_line
			(start -0.7874 0.4064)
			(end -0.7874 -0.4064)
			(stroke
				(width 0.1524)
				(type default)
			)
			(layer "F.SilkS")
		)
		(fp_line
			(start 0.7874 -0.4064)
			(end 0.7874 0.4064)
			(stroke
				(width 0.1524)
				(type default)
			)
			(layer "F.SilkS")
		)
		(fp_line
			(start 0.7874 0.4064)
			(end -0.7874 0.4064)
			(stroke
				(width 0.1524)
				(type default)
			)
			(layer "F.SilkS")
		)
		(fp_poly
			(pts
				(xy -0.508 0.2794) (xy -0.508 0.2286) (xy -0.635 0.2286) (xy -0.635 -0.254) (xy -0.5334 -0.254)
				(xy -0.5334 -0.2794) (xy 0.5334 -0.2794) (xy 0.5334 -0.254) (xy 0.635 -0.254) (xy 0.635 0.254) (xy 0.5334 0.254)
				(xy 0.5334 0.2794)
			)
			(stroke
				(width 0)
				(type default)
			)
			(fill no)
			(layer "F.CrtYd")
		)
		(pad "1" smd rect
			(at 0.40005 0)
			(size 0.4572 0.508)
			(layers "F.Cu" "F.Mask" "F.Paste")
			(net "PSU5_PS_KILL")
		)
		(pad "2" smd rect
			(at -0.40005 0)
			(size 0.4572 0.508)
			(layers "F.Cu" "F.Mask" "F.Paste")
			(net "GND")
		)
	)
)
